(kicad_pcb
	(version 20260206)
	(generator "pcbnew")
	(generator_version "10.0")
	(general
		(thickness 1.6)
		(legacy_teardrops no)
	)
	(paper "A4")
	(title_block
		(title "Wiwynn_Tioga_Pass_MB.brd")
		(comment 1 "Tioga Pass / footprints 3372-3378 of 4770")
	)
	(layers
		(0 "F.Cu" signal "TOP")
		(4 "In1.Cu" signal "L2GND")
		(6 "In2.Cu" signal "L3")
		(8 "In3.Cu" signal "L4GND")
		(10 "In4.Cu" signal "L5")
		(12 "In5.Cu" signal "L6GND")
		(14 "In6.Cu" signal "L7VCC")
		(16 "In7.Cu" signal "L8VCC")
		(18 "In8.Cu" signal "L9GND")
		(20 "In9.Cu" signal "L10")
		(22 "In10.Cu" signal "L11GND")
		(24 "In11.Cu" signal "L12")
		(26 "In12.Cu" signal "L13GND")
		(2 "B.Cu" signal "BOTTOM")
		(9 "F.Adhes" user "F.Adhesive")
		(11 "B.Adhes" user "B.Adhesive")
		(13 "F.Paste" user "Package Geometry/Pastemask Top")
		(15 "B.Paste" user "Package Geometry/Pastemask Bottom")
		(5 "F.SilkS" user "Ref Des/Silkscreen Top")
		(7 "B.SilkS" user "Ref Des/Silkscreen Bottom")
		(1 "F.Mask" user "Board Geometry/Soldermask Top")
		(3 "B.Mask" user "Board Geometry/Soldermask Bottom")
		(17 "Dwgs.User" user "User.Drawings")
		(19 "Cmts.User" user "User.Comments")
		(21 "Eco1.User" user "User.Eco1")
		(23 "Eco2.User" user "User.Eco2")
		(25 "Edge.Cuts" user "Board Geometry/Outline")
		(27 "Margin" user)
		(31 "F.CrtYd" user "Package Geometry/Place Bound Top")
		(29 "B.CrtYd" user "Package Geometry/Place Bound Bottom")
		(35 "F.Fab" user "Ref Des/Assembly Top")
		(33 "B.Fab" user "Ref Des/Assembly Bottom")
	)
	(footprint ""
		(layer "B.Cu")
		(at 111.000032 -17.7546 90)
		(property "Reference" "C7T4"
			(at -1.848866 0.752348 90)
			(unlocked yes)
			(layer "B.SilkS")
			(effects
				(font
					(size 1.27 0.9652)
					(thickness 0.1524)
				)
				(justify mirror)
			)
		)
		(property "Value" ""
			(at 0 0 90)
			(layer "B.Fab")
			(effects
				(font
					(size 1.27 1.27)
				)
				(justify mirror)
			)
		)
		(duplicate_pad_numbers_are_jumpers no)
		(fp_rect
			(start 0.500126 1.598422)
			(end -0.500126 -0.201422)
			(stroke
				(width 0)
				(type default)
			)
			(fill no)
			(layer "B.CrtYd")
		)
		(fp_line
			(start 0.500126 -0.201422)
			(end -0.500126 -0.201422)
			(stroke
				(width 0.1)
				(type default)
			)
			(layer "B.Fab")
		)
		(fp_line
			(start -0.500126 -0.201422)
			(end -0.500126 1.598422)
			(stroke
				(width 0.1)
				(type default)
			)
			(layer "B.Fab")
		)
		(fp_line
			(start 0.500126 1.598422)
			(end 0.500126 -0.201422)
			(stroke
				(width 0.1)
				(type default)
			)
			(layer "B.Fab")
		)
		(fp_line
			(start -0.500126 1.598422)
			(end 0.500126 1.598422)
			(stroke
				(width 0.1)
				(type default)
			)
			(layer "B.Fab")
		)
		(pad "1" smd rect
			(at 0 0)
			(size 0.889 0.9906)
			(layers "B.Cu" "B.Mask" "B.Paste")
			(net "PVDDQ_GHJ")
		)
		(pad "2" smd rect
			(at 0 1.397)
			(size 0.889 0.9906)
			(layers "B.Cu" "B.Mask" "B.Paste")
			(net "GND")
		)
		(zone
			(layer "B.Cu")
			(hatch none 0.5)
			(connect_pads
				(clearance 0)
			)
			(min_thickness 0.25)
			(keepout
				(tracks allowed)
				(vias not_allowed)
				(pads allowed)
				(copperpour not_allowed)
				(footprints allowed)
			)
			(placement
				(enabled no)
				(sheetname "")
			)
			(fill
				(thermal_gap 0.5)
				(thermal_bridge_width 0.5)
				(island_removal_mode 0)
			)
			(polygon
				(pts
					(xy 111.952532 -18.2499) (xy 111.444532 -18.2499) (xy 111.444532 -17.2593) (xy 111.952532 -17.2593)
				)
			)
		)
		(zone
			(layer "B.Cu")
			(hatch none 0.5)
			(connect_pads
				(clearance 0)
			)
			(min_thickness 0.25)
			(keepout
				(tracks not_allowed)
				(vias allowed)
				(pads allowed)
				(copperpour not_allowed)
				(footprints allowed)
			)
			(placement
				(enabled no)
				(sheetname "")
			)
			(fill
				(thermal_gap 0.5)
				(thermal_bridge_width 0.5)
				(island_removal_mode 0)
			)
			(polygon
				(pts
					(xy 111.952532 -18.2499) (xy 111.444532 -18.2499) (xy 111.444532 -17.2593) (xy 111.952532 -17.2593)
				)
			)
		)
	)
	(footprint ""
		(layer "B.Cu")
		(at 87.158068 -3.3528 -90)
		(property "Reference" "C5G86"
			(at -1.14681 0.76708 0)
			(unlocked yes)
			(layer "B.SilkS")
			(effects
				(font
					(size 0.7874 0.5842)
					(thickness 0.1524)
				)
				(justify mirror)
			)
		)
		(property "Value" ""
			(at 0 0 90)
			(layer "B.Fab")
			(effects
				(font
					(size 1.27 1.27)
				)
				(justify mirror)
			)
		)
		(duplicate_pad_numbers_are_jumpers no)
		(fp_rect
			(start 0.4953 1.6002)
			(end -0.4953 -0.2032)
			(stroke
				(width 0)
				(type default)
			)
			(fill no)
			(layer "B.CrtYd")
		)
		(fp_line
			(start -0.4953 1.6002)
			(end 0.4953 1.6002)
			(stroke
				(width 0.1)
				(type default)
			)
			(layer "B.Fab")
		)
		(fp_line
			(start 0.4953 1.6002)
			(end 0.4953 -0.2032)
			(stroke
				(width 0.1)
				(type default)
			)
			(layer "B.Fab")
		)
		(fp_line
			(start -0.4953 -0.2032)
			(end -0.4953 1.6002)
			(stroke
				(width 0.1)
				(type default)
			)
			(layer "B.Fab")
		)
		(fp_line
			(start 0.4953 -0.2032)
			(end -0.4953 -0.2032)
			(stroke
				(width 0.1)
				(type default)
			)
			(layer "B.Fab")
		)
		(pad "1" smd rect
			(at 0 0 90)
			(size 0.762 0.889)
			(layers "B.Cu" "B.Mask" "B.Paste")
			(net "PVDDQ_GHJ")
		)
		(pad "2" smd rect
			(at 0 1.397 90)
			(size 0.762 0.889)
			(layers "B.Cu" "B.Mask" "B.Paste")
			(net "GND")
		)
		(zone
			(layer "B.Cu")
			(hatch none 0.5)
			(connect_pads
				(clearance 0)
			)
			(min_thickness 0.25)
			(keepout
				(tracks not_allowed)
				(vias allowed)
				(pads allowed)
				(copperpour not_allowed)
				(footprints allowed)
			)
			(placement
				(enabled no)
				(sheetname "")
			)
			(fill
				(thermal_gap 0.5)
				(thermal_bridge_width 0.5)
				(island_removal_mode 0)
			)
			(polygon
				(pts
					(xy 86.205568 -2.9718) (xy 86.713568 -2.9718) (xy 86.713568 -3.7338) (xy 86.205568 -3.7338)
				)
			)
		)
	)
	(footprint ""
		(layer "B.Cu")
		(at 394.589 -88.2015)
		(property "Reference" "R2N20"
			(at 0 0 0)
			(layer "B.SilkS")
			(hide yes)
			(effects
				(font
					(size 1.27 1.27)
				)
				(justify mirror)
			)
		)
		(property "Value" ""
			(at 0 0 0)
			(layer "B.Fab")
			(effects
				(font
					(size 1.27 1.27)
				)
				(justify mirror)
			)
		)
		(duplicate_pad_numbers_are_jumpers no)
		(fp_poly
			(pts
				(xy 0.2794 -0.1016) (xy -0.2794 -0.1016) (xy -0.2794 0.9906) (xy 0.2794 0.9906)
			)
			(stroke
				(width 0)
				(type default)
			)
			(fill no)
			(layer "B.CrtYd")
		)
		(fp_line
			(start -0.2794 -0.1016)
			(end 0.2794 -0.1016)
			(stroke
				(width 0.1)
				(type default)
			)
			(layer "B.Fab")
		)
		(fp_line
			(start -0.2794 0.9906)
			(end -0.2794 -0.1016)
			(stroke
				(width 0.1)
				(type default)
			)
			(layer "B.Fab")
		)
		(fp_line
			(start 0.2794 -0.1016)
			(end 0.2794 0.9906)
			(stroke
				(width 0.1)
				(type default)
			)
			(layer "B.Fab")
		)
		(fp_line
			(start 0.2794 0.9906)
			(end -0.2794 0.9906)
			(stroke
				(width 0.1)
				(type default)
			)
			(layer "B.Fab")
		)
		(pad "1" smd rect
			(at 0 0 180)
			(size 0.508 0.508)
			(layers "B.Cu" "B.Mask" "B.Paste")
			(net "SMB_LAN_STBY_LVC3_SDA_R2")
		)
		(pad "2" smd rect
			(at 0 0.889 180)
			(size 0.508 0.508)
			(layers "B.Cu" "B.Mask" "B.Paste")
			(net "SMB_LAN_STBY_LVC3_SDA")
		)
		(zone
			(layer "B.Cu")
			(hatch none 0.5)
			(connect_pads
				(clearance 0)
			)
			(min_thickness 0.25)
			(keepout
				(tracks allowed)
				(vias not_allowed)
				(pads allowed)
				(copperpour not_allowed)
				(footprints allowed)
			)
			(placement
				(enabled no)
				(sheetname "")
			)
			(fill
				(thermal_gap 0.5)
				(thermal_bridge_width 0.5)
				(island_removal_mode 0)
			)
			(polygon
				(pts
					(xy 394.843 -87.9475) (xy 394.335 -87.9475) (xy 394.335 -87.5665) (xy 394.843 -87.5665)
				)
			)
		)
		(zone
			(layer "B.Cu")
			(hatch none 0.5)
			(connect_pads
				(clearance 0)
			)
			(min_thickness 0.25)
			(keepout
				(tracks not_allowed)
				(vias allowed)
				(pads allowed)
				(copperpour not_allowed)
				(footprints allowed)
			)
			(placement
				(enabled no)
				(sheetname "")
			)
			(fill
				(thermal_gap 0.5)
				(thermal_bridge_width 0.5)
				(island_removal_mode 0)
			)
			(polygon
				(pts
					(xy 394.843 -87.5665) (xy 394.335 -87.5665) (xy 394.335 -87.9475) (xy 394.843 -87.9475)
				)
			)
		)
	)
	(footprint ""
		(layer "B.Cu")
		(at 413.5755 -17.526 -90)
		(property "Reference" "R2U45"
			(at 0 0 90)
			(layer "B.SilkS")
			(hide yes)
			(effects
				(font
					(size 1.27 1.27)
				)
				(justify mirror)
			)
		)
		(property "Value" ""
			(at 0 0 90)
			(layer "B.Fab")
			(effects
				(font
					(size 1.27 1.27)
				)
				(justify mirror)
			)
		)
		(duplicate_pad_numbers_are_jumpers no)
		(fp_poly
			(pts
				(xy 0.2794 -0.1016) (xy -0.2794 -0.1016) (xy -0.2794 0.9906) (xy 0.2794 0.9906)
			)
			(stroke
				(width 0)
				(type default)
			)
			(fill no)
			(layer "B.CrtYd")
		)
		(fp_line
			(start -0.2794 0.9906)
			(end -0.2794 -0.1016)
			(stroke
				(width 0.1)
				(type default)
			)
			(layer "B.Fab")
		)
		(fp_line
			(start 0.2794 0.9906)
			(end -0.2794 0.9906)
			(stroke
				(width 0.1)
				(type default)
			)
			(layer "B.Fab")
		)
		(fp_line
			(start -0.2794 -0.1016)
			(end 0.2794 -0.1016)
			(stroke
				(width 0.1)
				(type default)
			)
			(layer "B.Fab")
		)
		(fp_line
			(start 0.2794 -0.1016)
			(end 0.2794 0.9906)
			(stroke
				(width 0.1)
				(type default)
			)
			(layer "B.Fab")
		)
		(pad "1" smd rect
			(at 0 0 90)
			(size 0.508 0.508)
			(layers "B.Cu" "B.Mask" "B.Paste")
			(net "H_CPU1_MEMKLM_MEMHOT_LVT3_N")
		)
		(pad "2" smd rect
			(at 0 0.889 90)
			(size 0.508 0.508)
			(layers "B.Cu" "B.Mask" "B.Paste")
			(net "H_CPU1_MEMKLM_MEMHOT_PCH_N")
		)
		(zone
			(layer "B.Cu")
			(hatch none 0.5)
			(connect_pads
				(clearance 0)
			)
			(min_thickness 0.25)
			(keepout
				(tracks not_allowed)
				(vias allowed)
				(pads allowed)
				(copperpour not_allowed)
				(footprints allowed)
			)
			(placement
				(enabled no)
				(sheetname "")
			)
			(fill
				(thermal_gap 0.5)
				(thermal_bridge_width 0.5)
				(island_removal_mode 0)
			)
			(polygon
				(pts
					(xy 412.9405 -17.272) (xy 412.9405 -17.78) (xy 413.3215 -17.78) (xy 413.3215 -17.272)
				)
			)
		)
		(zone
			(layer "B.Cu")
			(hatch none 0.5)
			(connect_pads
				(clearance 0)
			)
			(min_thickness 0.25)
			(keepout
				(tracks allowed)
				(vias not_allowed)
				(pads allowed)
				(copperpour not_allowed)
				(footprints allowed)
			)
			(placement
				(enabled no)
				(sheetname "")
			)
			(fill
				(thermal_gap 0.5)
				(thermal_bridge_width 0.5)
				(island_removal_mode 0)
			)
			(polygon
				(pts
					(xy 413.3215 -17.272) (xy 413.3215 -17.78) (xy 412.9405 -17.78) (xy 412.9405 -17.272)
				)
			)
		)
	)
	(footprint ""
		(layer "B.Cu")
		(at 45.212 -62.611 -90)
		(property "Reference" "C9R3"
			(at -1.75133 -3.429 0)
			(unlocked yes)
			(layer "B.SilkS")
			(effects
				(font
					(size 0.7874 0.5842)
					(thickness 0.1524)
				)
				(justify mirror)
			)
		)
		(property "Value" ""
			(at 0 0 90)
			(layer "B.Fab")
			(effects
				(font
					(size 1.27 1.27)
				)
				(justify mirror)
			)
		)
		(duplicate_pad_numbers_are_jumpers no)
		(fp_line
			(start -2.286 7.366)
			(end -1.600708 7.366)
			(stroke
				(width 0.1524)
				(type default)
			)
			(layer "B.SilkS")
		)
		(fp_line
			(start -2.286 7.366)
			(end -2.286 1.63195)
			(stroke
				(width 0.1524)
				(type default)
			)
			(layer "B.SilkS")
		)
		(fp_line
			(start 2.286 7.366)
			(end 1.60147 7.366)
			(stroke
				(width 0.1524)
				(type default)
			)
			(layer "B.SilkS")
		)
		(fp_line
			(start 2.286 7.366)
			(end 2.286 1.632712)
			(stroke
				(width 0.1524)
				(type default)
			)
			(layer "B.SilkS")
		)
		(fp_line
			(start -2.504948 1.633728)
			(end -1.6002 1.633728)
			(stroke
				(width 0.1524)
				(type default)
			)
			(layer "B.SilkS")
		)
		(fp_line
			(start 2.563114 1.633728)
			(end 1.6002 1.633728)
			(stroke
				(width 0.1524)
				(type default)
			)
			(layer "B.SilkS")
		)
		(fp_line
			(start -2.504948 -1.616456)
			(end -2.504948 1.633728)
			(stroke
				(width 0.1524)
				(type default)
			)
			(layer "B.SilkS")
		)
		(fp_line
			(start -1.6002 -1.616456)
			(end -2.504948 -1.616456)
			(stroke
				(width 0.1524)
				(type default)
			)
			(layer "B.SilkS")
		)
		(fp_line
			(start 1.6002 -1.616456)
			(end 2.563114 -1.616456)
			(stroke
				(width 0.1524)
				(type default)
			)
			(layer "B.SilkS")
		)
		(fp_line
			(start 2.563114 -1.616456)
			(end 2.563114 1.633728)
			(stroke
				(width 0.1524)
				(type default)
			)
			(layer "B.SilkS")
		)
		(fp_rect
			(start 2.286 7.366)
			(end -2.286 -0.254)
			(stroke
				(width 0)
				(type default)
			)
			(fill no)
			(layer "B.CrtYd")
		)
		(fp_line
			(start -2.286 7.366)
			(end 2.286 7.366)
			(stroke
				(width 0.1)
				(type default)
			)
			(layer "B.Fab")
		)
		(fp_line
			(start 2.286 7.366)
			(end 2.286 -0.254)
			(stroke
				(width 0.1)
				(type default)
			)
			(layer "B.Fab")
		)
		(fp_line
			(start -2.286 -0.254)
			(end -2.286 7.366)
			(stroke
				(width 0.1)
				(type default)
			)
			(layer "B.Fab")
		)
		(fp_line
			(start 2.286 -0.254)
			(end -2.286 -0.254)
			(stroke
				(width 0.1)
				(type default)
			)
			(layer "B.Fab")
		)
		(pad "1" smd rect
			(at 0 0 90)
			(size 2.54 3.048)
			(layers "B.Cu" "B.Mask" "B.Paste")
			(net "PVCCIN_CPU1")
		)
		(pad "2" smd rect
			(at 0 7.112 90)
			(size 2.54 3.048)
			(layers "B.Cu" "B.Mask" "B.Paste")
			(net "GND")
		)
	)
	(footprint ""
		(layer "B.Cu")
		(at 487.160062 -28.4226 180)
		(property "Reference" "R1R6"
			(at 0.8382 -0.67818 180)
			(unlocked yes)
			(layer "B.SilkS")
			(effects
				(font
					(size 0.4064 0.254)
					(thickness 0.1524)
				)
				(justify left mirror)
			)
		)
		(property "Value" ""
			(at 0 0 0)
			(layer "B.Fab")
			(effects
				(font
					(size 1.27 1.27)
				)
				(justify mirror)
			)
		)
		(duplicate_pad_numbers_are_jumpers no)
		(fp_poly
			(pts
				(xy 0.2794 -0.1016) (xy -0.2794 -0.1016) (xy -0.2794 0.9906) (xy 0.2794 0.9906)
			)
			(stroke
				(width 0)
				(type default)
			)
			(fill no)
			(layer "B.CrtYd")
		)
		(fp_line
			(start 0.2794 0.9906)
			(end -0.2794 0.9906)
			(stroke
				(width 0.1)
				(type default)
			)
			(layer "B.Fab")
		)
		(fp_line
			(start 0.2794 -0.1016)
			(end 0.2794 0.9906)
			(stroke
				(width 0.1)
				(type default)
			)
			(layer "B.Fab")
		)
		(fp_line
			(start -0.2794 0.9906)
			(end -0.2794 -0.1016)
			(stroke
				(width 0.1)
				(type default)
			)
			(layer "B.Fab")
		)
		(fp_line
			(start -0.2794 -0.1016)
			(end 0.2794 -0.1016)
			(stroke
				(width 0.1)
				(type default)
			)
			(layer "B.Fab")
		)
		(pad "1" smd rect
			(at 0 0)
			(size 0.508 0.508)
			(layers "B.Cu" "B.Mask" "B.Paste")
			(net "SPI_NIC_MOSI")
		)
		(pad "2" smd rect
			(at 0 0.889)
			(size 0.508 0.508)
			(layers "B.Cu" "B.Mask" "B.Paste")
			(net "GND")
		)
		(zone
			(layer "B.Cu")
			(hatch none 0.5)
			(connect_pads
				(clearance 0)
			)
			(min_thickness 0.25)
			(keepout
				(tracks not_allowed)
				(vias allowed)
				(pads allowed)
				(copperpour not_allowed)
				(footprints allowed)
			)
			(placement
				(enabled no)
				(sheetname "")
			)
			(fill
				(thermal_gap 0.5)
				(thermal_bridge_width 0.5)
				(island_removal_mode 0)
			)
			(polygon
				(pts
					(xy 486.906062 -29.0576) (xy 487.414062 -29.0576) (xy 487.414062 -28.6766) (xy 486.906062 -28.6766)
				)
			)
		)
		(zone
			(layer "B.Cu")
			(hatch none 0.5)
			(connect_pads
				(clearance 0)
			)
			(min_thickness 0.25)
			(keepout
				(tracks allowed)
				(vias not_allowed)
				(pads allowed)
				(copperpour not_allowed)
				(footprints allowed)
			)
			(placement
				(enabled no)
				(sheetname "")
			)
			(fill
				(thermal_gap 0.5)
				(thermal_bridge_width 0.5)
				(island_removal_mode 0)
			)
			(polygon
				(pts
					(xy 486.906062 -28.6766) (xy 487.414062 -28.6766) (xy 487.414062 -29.0576) (xy 486.906062 -29.0576)
				)
			)
		)
	)
	(footprint ""
		(layer "B.Cu")
		(at 45.212 -73.279 -90)
		(property "Reference" "C9P18"
			(at -0.98933 -3.81 0)
			(unlocked yes)
			(layer "B.SilkS")
			(effects
				(font
					(size 0.7874 0.5842)
					(thickness 0.1524)
				)
				(justify mirror)
			)
		)
		(property "Value" ""
			(at 0 0 90)
			(layer "B.Fab")
			(effects
				(font
					(size 1.27 1.27)
				)
				(justify mirror)
			)
		)
		(duplicate_pad_numbers_are_jumpers no)
		(fp_line
			(start -2.286 7.366)
			(end -1.600708 7.366)
			(stroke
				(width 0.1524)
				(type default)
			)
			(layer "B.SilkS")
		)
		(fp_line
			(start -2.286 7.366)
			(end -2.286 1.63195)
			(stroke
				(width 0.1524)
				(type default)
			)
			(layer "B.SilkS")
		)
		(fp_line
			(start 2.286 7.366)
			(end 1.60147 7.366)
			(stroke
				(width 0.1524)
				(type default)
			)
			(layer "B.SilkS")
		)
		(fp_line
			(start 2.286 7.366)
			(end 2.286 1.632712)
			(stroke
				(width 0.1524)
				(type default)
			)
			(layer "B.SilkS")
		)
		(fp_line
			(start -2.504948 1.633728)
			(end -1.6002 1.633728)
			(stroke
				(width 0.1524)
				(type default)
			)
			(layer "B.SilkS")
		)
		(fp_line
			(start 2.563114 1.633728)
			(end 1.6002 1.633728)
			(stroke
				(width 0.1524)
				(type default)
			)
			(layer "B.SilkS")
		)
		(fp_line
			(start -2.504948 -1.616456)
			(end -2.504948 1.633728)
			(stroke
				(width 0.1524)
				(type default)
			)
			(layer "B.SilkS")
		)
		(fp_line
			(start -1.6002 -1.616456)
			(end -2.504948 -1.616456)
			(stroke
				(width 0.1524)
				(type default)
			)
			(layer "B.SilkS")
		)
		(fp_line
			(start 1.6002 -1.616456)
			(end 2.563114 -1.616456)
			(stroke
				(width 0.1524)
				(type default)
			)
			(layer "B.SilkS")
		)
		(fp_line
			(start 2.563114 -1.616456)
			(end 2.563114 1.633728)
			(stroke
				(width 0.1524)
				(type default)
			)
			(layer "B.SilkS")
		)
		(fp_rect
			(start 2.286 7.366)
			(end -2.286 -0.254)
			(stroke
				(width 0)
				(type default)
			)
			(fill no)
			(layer "B.CrtYd")
		)
		(fp_line
			(start -2.286 7.366)
			(end 2.286 7.366)
			(stroke
				(width 0.1)
				(type default)
			)
			(layer "B.Fab")
		)
		(fp_line
			(start 2.286 7.366)
			(end 2.286 -0.254)
			(stroke
				(width 0.1)
				(type default)
			)
			(layer "B.Fab")
		)
		(fp_line
			(start -2.286 -0.254)
			(end -2.286 7.366)
			(stroke
				(width 0.1)
				(type default)
			)
			(layer "B.Fab")
		)
		(fp_line
			(start 2.286 -0.254)
			(end -2.286 -0.254)
			(stroke
				(width 0.1)
				(type default)
			)
			(layer "B.Fab")
		)
		(pad "1" smd rect
			(at 0 0 90)
			(size 2.54 3.048)
			(layers "B.Cu" "B.Mask" "B.Paste")
			(net "PVCCIN_CPU1")
		)
		(pad "2" smd rect
			(at 0 7.112 90)
			(size 2.54 3.048)
			(layers "B.Cu" "B.Mask" "B.Paste")
			(net "GND")
		)
	)
)
